(kicad_pcb
	(version 20260206)
	(generator "pcbnew")
	(generator_version "10.0")
	(general
		(thickness 1.6)
		(legacy_teardrops no)
	)
	(paper "A4")
	(title_block
		(title "Wiwynn_Tioga_Pass_MB.brd")
		(comment 1 "Tioga Pass / footprints 4263-4268 of 4770")
	)
	(layers
		(0 "F.Cu" signal "TOP")
		(4 "In1.Cu" signal "L2GND")
		(6 "In2.Cu" signal "L3")
		(8 "In3.Cu" signal "L4GND")
		(10 "In4.Cu" signal "L5")
		(12 "In5.Cu" signal "L6GND")
		(14 "In6.Cu" signal "L7VCC")
		(16 "In7.Cu" signal "L8VCC")
		(18 "In8.Cu" signal "L9GND")
		(20 "In9.Cu" signal "L10")
		(22 "In10.Cu" signal "L11GND")
		(24 "In11.Cu" signal "L12")
		(26 "In12.Cu" signal "L13GND")
		(2 "B.Cu" signal "BOTTOM")
		(9 "F.Adhes" user "F.Adhesive")
		(11 "B.Adhes" user "B.Adhesive")
		(13 "F.Paste" user "Package Geometry/Pastemask Top")
		(15 "B.Paste" user "Package Geometry/Pastemask Bottom")
		(5 "F.SilkS" user "Ref Des/Silkscreen Top")
		(7 "B.SilkS" user "Ref Des/Silkscreen Bottom")
		(1 "F.Mask" user "Board Geometry/Soldermask Top")
		(3 "B.Mask" user "Board Geometry/Soldermask Bottom")
		(17 "Dwgs.User" user "User.Drawings")
		(19 "Cmts.User" user "User.Comments")
		(21 "Eco1.User" user "User.Eco1")
		(23 "Eco2.User" user "User.Eco2")
		(25 "Edge.Cuts" user "Board Geometry/Outline")
		(27 "Margin" user)
		(31 "F.CrtYd" user "Package Geometry/Place Bound Top")
		(29 "B.CrtYd" user "Package Geometry/Place Bound Bottom")
		(35 "F.Fab" user "Ref Des/Assembly Top")
		(33 "B.Fab" user "Ref Des/Assembly Bottom")
	)
	(footprint ""
		(layer "B.Cu")
		(at 10.2108 -124.9172)
		(property "Reference" "Q12W4"
			(at 0 0 0)
			(layer "B.SilkS")
			(hide yes)
			(effects
				(font
					(size 1.27 1.27)
				)
				(justify mirror)
			)
		)
		(property "Value" "*"
			(at 4.572 -7.6835 0)
			(unlocked yes)
			(layer "B.Fab")
			(hide yes)
			(effects
				(font
					(size 1.27 1.016)
					(thickness 0.1524)
				)
				(justify mirror)
			)
		)
		(property "Device Type" "BSL308C-H6327-GP_DISCRET-GB1-BA"
			(at 4.572 -9.2075 0)
			(unlocked yes)
			(layer "B.Fab")
			(hide yes)
			(effects
				(font
					(size 1.27 1.016)
					(thickness 0.1524)
				)
				(justify mirror)
			)
		)
		(duplicate_pad_numbers_are_jumpers no)
		(fp_line
			(start -1.102868 -0.081534)
			(end -1.102868 0.081534)
			(stroke
				(width 0.1524)
				(type default)
			)
			(layer "B.SilkS")
		)
		(fp_line
			(start -1.102868 0.081534)
			(end 1.8796 0.081534)
			(stroke
				(width 0.1524)
				(type default)
			)
			(layer "B.SilkS")
		)
		(fp_line
			(start 1.524 0)
			(end 1.8796 0.081534)
			(stroke
				(width 0.1524)
				(type default)
			)
			(layer "B.SilkS")
		)
		(fp_line
			(start 1.7018 0.3048)
			(end 1.7018 1.8796)
			(stroke
				(width 0.508)
				(type default)
			)
			(layer "B.SilkS")
		)
		(fp_line
			(start 1.8796 -0.081534)
			(end -1.102868 -0.081534)
			(stroke
				(width 0.1524)
				(type default)
			)
			(layer "B.SilkS")
		)
		(fp_line
			(start 1.8796 -0.081534)
			(end 1.524 0)
			(stroke
				(width 0.1524)
				(type default)
			)
			(layer "B.SilkS")
		)
		(fp_line
			(start 1.8796 0.081534)
			(end 1.8796 -0.081534)
			(stroke
				(width 0.1524)
				(type default)
			)
			(layer "B.SilkS")
		)
		(fp_poly
			(pts
				(xy 1.179068 0.081534) (xy 1.179068 -0.081534) (xy -1.102868 -0.081534) (xy -1.102868 0.081534)
			)
			(stroke
				(width 0)
				(type default)
			)
			(fill yes)
			(layer "B.SilkS")
		)
		(fp_rect
			(start 1.4478 1.2446)
			(end -1.4478 -1.2446)
			(stroke
				(width 0)
				(type default)
			)
			(fill no)
			(layer "B.CrtYd")
		)
		(fp_poly
			(pts
				(xy 1.4478 -1.23952) (xy 1.9558 -1.23952) (xy 1.9558 2.1336) (xy -1.9558 2.1336) (xy -1.9558 -2.1336)
				(xy 1.9558 -2.1336) (xy 1.9558 -1.2446) (xy -1.4478 -1.2446) (xy -1.4478 1.2446) (xy 1.4478 1.2446)
			)
			(stroke
				(width 0)
				(type default)
			)
			(fill no)
			(layer "B.CrtYd")
		)
		(fp_rect
			(start 1.9558 2.1336)
			(end -1.9558 -2.1336)
			(stroke
				(width 0)
				(type default)
			)
			(fill no)
			(layer "B.Fab")
		)
		(pad "1" smd rect
			(at 0.950468 0.995934 180)
			(size 0.4572 1.27)
			(layers "B.Cu" "B.Mask" "B.Paste")
			(net "PWRGD_PVDDQ_KLM")
		)
		(pad "2" smd rect
			(at 0 0.995934 180)
			(size 0.4572 1.27)
			(layers "B.Cu" "B.Mask" "B.Paste")
			(net "P12V_NVDIMM_KLM")
		)
		(pad "3" smd rect
			(at -0.950468 0.995934 180)
			(size 0.4572 1.27)
			(layers "B.Cu" "B.Mask" "B.Paste")
			(net "PWRGD_PVDDQ_KLM_N")
		)
		(pad "4" smd rect
			(at -0.950468 -0.995934 180)
			(size 0.4572 1.27)
			(layers "B.Cu" "B.Mask" "B.Paste")
			(net "P12V_NVDIMM_KLM_D")
		)
		(pad "5" smd rect
			(at 0 -0.995934 180)
			(size 0.4572 1.27)
			(layers "B.Cu" "B.Mask" "B.Paste")
			(net "GND")
		)
		(pad "6" smd rect
			(at 0.950468 -0.995934 180)
			(size 0.4572 1.27)
			(layers "B.Cu" "B.Mask" "B.Paste")
			(net "PWRGD_PVDDQ_KLM_N")
		)
	)
	(footprint ""
		(layer "B.Cu")
		(at 374.744742 -73.095104)
		(property "Reference" "C2P5"
			(at 0 0 0)
			(layer "B.SilkS")
			(hide yes)
			(effects
				(font
					(size 1.27 1.27)
				)
				(justify mirror)
			)
		)
		(property "Value" ""
			(at 0 0 0)
			(layer "B.Fab")
			(effects
				(font
					(size 1.27 1.27)
				)
				(justify mirror)
			)
		)
		(duplicate_pad_numbers_are_jumpers no)
		(fp_rect
			(start 0.2794 0.9144)
			(end -0.2794 -0.1143)
			(stroke
				(width 0)
				(type default)
			)
			(fill no)
			(layer "B.CrtYd")
		)
		(fp_line
			(start -0.2794 -0.1143)
			(end -0.2794 0.9144)
			(stroke
				(width 0.1)
				(type default)
			)
			(layer "B.Fab")
		)
		(fp_line
			(start -0.2794 0.9144)
			(end 0.2794 0.9144)
			(stroke
				(width 0.1)
				(type default)
			)
			(layer "B.Fab")
		)
		(fp_line
			(start 0.2794 -0.1143)
			(end -0.2794 -0.1143)
			(stroke
				(width 0.1)
				(type default)
			)
			(layer "B.Fab")
		)
		(fp_line
			(start 0.2794 0.9144)
			(end 0.2794 -0.1143)
			(stroke
				(width 0.1)
				(type default)
			)
			(layer "B.Fab")
		)
		(pad "1" smd custom
			(at 0 0 270)
			(size 0.10414 0.10414)
			(layers "B.Cu" "B.Mask" "B.Paste")
			(net "P3V3_STBY")
			(options
				(clearance outline)
				(anchor circle)
			)
			(primitives
				(gr_poly
					(pts
						(xy -0.20828 -0.08636) (xy -0.20828 0.08636) (xy -0.08636 0.20828) (xy 0.086614 0.20828) (xy 0.20828 0.086614)
						(xy 0.20828 -0.08636) (xy 0.08636 -0.20828) (xy -0.08636 -0.20828)
					)
					(width 0)
					(fill yes)
				)
			)
		)
		(pad "2" smd custom
			(at 0 0.8001 270)
			(size 0.10414 0.10414)
			(layers "B.Cu" "B.Mask" "B.Paste")
			(net "GND")
			(options
				(clearance outline)
				(anchor circle)
			)
			(primitives
				(gr_poly
					(pts
						(xy -0.20828 -0.08636) (xy -0.20828 0.08636) (xy -0.08636 0.20828) (xy 0.086614 0.20828) (xy 0.20828 0.086614)
						(xy 0.20828 -0.08636) (xy 0.08636 -0.20828) (xy -0.08636 -0.20828)
					)
					(width 0)
					(fill yes)
				)
			)
		)
		(zone
			(layer "B.Cu")
			(hatch none 0.5)
			(connect_pads
				(clearance 0)
			)
			(min_thickness 0.25)
			(keepout
				(tracks not_allowed)
				(vias allowed)
				(pads allowed)
				(copperpour not_allowed)
				(footprints allowed)
			)
			(placement
				(enabled no)
				(sheetname "")
			)
			(fill
				(thermal_gap 0.5)
				(thermal_bridge_width 0.5)
				(island_removal_mode 0)
			)
			(polygon
				(pts
					(xy 374.832372 -72.885554) (xy 374.832372 -72.504554) (xy 374.657112 -72.504554) (xy 374.656858 -72.885554)
				)
			)
		)
		(zone
			(layer "B.Cu")
			(hatch none 0.5)
			(connect_pads
				(clearance 0)
			)
			(min_thickness 0.25)
			(keepout
				(tracks allowed)
				(vias not_allowed)
				(pads allowed)
				(copperpour not_allowed)
				(footprints allowed)
			)
			(placement
				(enabled no)
				(sheetname "")
			)
			(fill
				(thermal_gap 0.5)
				(thermal_bridge_width 0.5)
				(island_removal_mode 0)
			)
			(polygon
				(pts
					(xy 374.832372 -72.885554) (xy 374.832372 -72.504554) (xy 374.657112 -72.504554) (xy 374.656858 -72.885554)
				)
			)
		)
	)
	(footprint ""
		(layer "B.Cu")
		(at 390.7155 -38.62451 -90)
		(property "Reference" "C2T4"
			(at 0 0 90)
			(layer "B.SilkS")
			(hide yes)
			(effects
				(font
					(size 1.27 1.27)
				)
				(justify mirror)
			)
		)
		(property "Value" ""
			(at 0 0 90)
			(layer "B.Fab")
			(effects
				(font
					(size 1.27 1.27)
				)
				(justify mirror)
			)
		)
		(duplicate_pad_numbers_are_jumpers no)
		(fp_poly
			(pts
				(xy -0.3048 -0.1016) (xy -0.3048 0.9906) (xy 0.3048 0.9906) (xy 0.3048 -0.1016)
			)
			(stroke
				(width 0)
				(type default)
			)
			(fill no)
			(layer "B.CrtYd")
		)
		(fp_line
			(start -0.3048 0.9906)
			(end -0.3048 -0.1016)
			(stroke
				(width 0.1)
				(type default)
			)
			(layer "B.Fab")
		)
		(fp_line
			(start 0.3048 0.9906)
			(end -0.3048 0.9906)
			(stroke
				(width 0.1)
				(type default)
			)
			(layer "B.Fab")
		)
		(fp_line
			(start -0.3048 -0.1016)
			(end 0.3048 -0.1016)
			(stroke
				(width 0.1)
				(type default)
			)
			(layer "B.Fab")
		)
		(fp_line
			(start 0.3048 -0.1016)
			(end 0.3048 0.9906)
			(stroke
				(width 0.1)
				(type default)
			)
			(layer "B.Fab")
		)
		(pad "1" smd rect
			(at 0 0 90)
			(size 0.508 0.508)
			(layers "B.Cu" "B.Mask" "B.Paste")
			(net "P3V3")
		)
		(pad "2" smd rect
			(at 0 0.889 90)
			(size 0.508 0.508)
			(layers "B.Cu" "B.Mask" "B.Paste")
			(net "GND")
		)
		(zone
			(layer "B.Cu")
			(hatch none 0.5)
			(connect_pads
				(clearance 0)
			)
			(min_thickness 0.25)
			(keepout
				(tracks not_allowed)
				(vias allowed)
				(pads allowed)
				(copperpour not_allowed)
				(footprints allowed)
			)
			(placement
				(enabled no)
				(sheetname "")
			)
			(fill
				(thermal_gap 0.5)
				(thermal_bridge_width 0.5)
				(island_removal_mode 0)
			)
			(polygon
				(pts
					(xy 390.0805 -38.37051) (xy 390.0805 -38.87851) (xy 390.4615 -38.87851) (xy 390.4615 -38.37051)
				)
			)
		)
		(zone
			(layer "B.Cu")
			(hatch none 0.5)
			(connect_pads
				(clearance 0)
			)
			(min_thickness 0.25)
			(keepout
				(tracks allowed)
				(vias not_allowed)
				(pads allowed)
				(copperpour not_allowed)
				(footprints allowed)
			)
			(placement
				(enabled no)
				(sheetname "")
			)
			(fill
				(thermal_gap 0.5)
				(thermal_bridge_width 0.5)
				(island_removal_mode 0)
			)
			(polygon
				(pts
					(xy 390.4615 -38.37051) (xy 390.4615 -38.87851) (xy 390.0805 -38.87851) (xy 390.0805 -38.37051)
				)
			)
		)
	)
	(footprint ""
		(layer "B.Cu")
		(at 161.78022 -123.0757 180)
		(property "Reference" "R7M4"
			(at 0 0 0)
			(layer "B.SilkS")
			(hide yes)
			(effects
				(font
					(size 1.27 1.27)
				)
				(justify mirror)
			)
		)
		(property "Value" ""
			(at 0 0 0)
			(layer "B.Fab")
			(effects
				(font
					(size 1.27 1.27)
				)
				(justify mirror)
			)
		)
		(duplicate_pad_numbers_are_jumpers no)
		(fp_poly
			(pts
				(xy 0.2794 -0.1016) (xy -0.2794 -0.1016) (xy -0.2794 0.9906) (xy 0.2794 0.9906)
			)
			(stroke
				(width 0)
				(type default)
			)
			(fill no)
			(layer "B.CrtYd")
		)
		(fp_line
			(start 0.2794 0.9906)
			(end -0.2794 0.9906)
			(stroke
				(width 0.1)
				(type default)
			)
			(layer "B.Fab")
		)
		(fp_line
			(start 0.2794 -0.1016)
			(end 0.2794 0.9906)
			(stroke
				(width 0.1)
				(type default)
			)
			(layer "B.Fab")
		)
		(fp_line
			(start -0.2794 0.9906)
			(end -0.2794 -0.1016)
			(stroke
				(width 0.1)
				(type default)
			)
			(layer "B.Fab")
		)
		(fp_line
			(start -0.2794 -0.1016)
			(end 0.2794 -0.1016)
			(stroke
				(width 0.1)
				(type default)
			)
			(layer "B.Fab")
		)
		(pad "1" smd rect
			(at 0 0)
			(size 0.508 0.508)
			(layers "B.Cu" "B.Mask" "B.Paste")
			(net "SMB_DDR_KLM_VPP_SCL_R")
		)
		(pad "2" smd rect
			(at 0 0.889)
			(size 0.508 0.508)
			(layers "B.Cu" "B.Mask" "B.Paste")
			(net "SMB_DDR_KLM_VPP_SCL")
		)
		(zone
			(layer "B.Cu")
			(hatch none 0.5)
			(connect_pads
				(clearance 0)
			)
			(min_thickness 0.25)
			(keepout
				(tracks not_allowed)
				(vias allowed)
				(pads allowed)
				(copperpour not_allowed)
				(footprints allowed)
			)
			(placement
				(enabled no)
				(sheetname "")
			)
			(fill
				(thermal_gap 0.5)
				(thermal_bridge_width 0.5)
				(island_removal_mode 0)
			)
			(polygon
				(pts
					(xy 161.52622 -123.7107) (xy 162.03422 -123.7107) (xy 162.03422 -123.3297) (xy 161.52622 -123.3297)
				)
			)
		)
		(zone
			(layer "B.Cu")
			(hatch none 0.5)
			(connect_pads
				(clearance 0)
			)
			(min_thickness 0.25)
			(keepout
				(tracks allowed)
				(vias not_allowed)
				(pads allowed)
				(copperpour not_allowed)
				(footprints allowed)
			)
			(placement
				(enabled no)
				(sheetname "")
			)
			(fill
				(thermal_gap 0.5)
				(thermal_bridge_width 0.5)
				(island_removal_mode 0)
			)
			(polygon
				(pts
					(xy 161.52622 -123.3297) (xy 162.03422 -123.3297) (xy 162.03422 -123.7107) (xy 161.52622 -123.7107)
				)
			)
		)
	)
	(footprint ""
		(layer "B.Cu")
		(at 451.7898 -5.5118 90)
		(property "Reference" "R6W2"
			(at 0.8382 -0.67818 90)
			(unlocked yes)
			(layer "B.SilkS")
			(effects
				(font
					(size 0.4064 0.254)
					(thickness 0.1524)
				)
				(justify left mirror)
			)
		)
		(property "Value" ""
			(at 0 0 90)
			(layer "B.Fab")
			(effects
				(font
					(size 1.27 1.27)
				)
				(justify mirror)
			)
		)
		(duplicate_pad_numbers_are_jumpers no)
		(fp_poly
			(pts
				(xy 0.2794 -0.1016) (xy -0.2794 -0.1016) (xy -0.2794 0.9906) (xy 0.2794 0.9906)
			)
			(stroke
				(width 0)
				(type default)
			)
			(fill no)
			(layer "B.CrtYd")
		)
		(fp_line
			(start 0.2794 -0.1016)
			(end 0.2794 0.9906)
			(stroke
				(width 0.1)
				(type default)
			)
			(layer "B.Fab")
		)
		(fp_line
			(start -0.2794 -0.1016)
			(end 0.2794 -0.1016)
			(stroke
				(width 0.1)
				(type default)
			)
			(layer "B.Fab")
		)
		(fp_line
			(start 0.2794 0.9906)
			(end -0.2794 0.9906)
			(stroke
				(width 0.1)
				(type default)
			)
			(layer "B.Fab")
		)
		(fp_line
			(start -0.2794 0.9906)
			(end -0.2794 -0.1016)
			(stroke
				(width 0.1)
				(type default)
			)
			(layer "B.Fab")
		)
		(pad "1" smd rect
			(at 0 0 270)
			(size 0.508 0.508)
			(layers "B.Cu" "B.Mask" "B.Paste")
			(net "PD_UV_HIGH_SET")
		)
		(pad "2" smd rect
			(at 0 0.889 270)
			(size 0.508 0.508)
			(layers "B.Cu" "B.Mask" "B.Paste")
			(net "GND")
		)
		(zone
			(layer "B.Cu")
			(hatch none 0.5)
			(connect_pads
				(clearance 0)
			)
			(min_thickness 0.25)
			(keepout
				(tracks allowed)
				(vias not_allowed)
				(pads allowed)
				(copperpour not_allowed)
				(footprints allowed)
			)
			(placement
				(enabled no)
				(sheetname "")
			)
			(fill
				(thermal_gap 0.5)
				(thermal_bridge_width 0.5)
				(island_removal_mode 0)
			)
			(polygon
				(pts
					(xy 452.0438 -5.7658) (xy 452.0438 -5.2578) (xy 452.4248 -5.2578) (xy 452.4248 -5.7658)
				)
			)
		)
		(zone
			(layer "B.Cu")
			(hatch none 0.5)
			(connect_pads
				(clearance 0)
			)
			(min_thickness 0.25)
			(keepout
				(tracks not_allowed)
				(vias allowed)
				(pads allowed)
				(copperpour not_allowed)
				(footprints allowed)
			)
			(placement
				(enabled no)
				(sheetname "")
			)
			(fill
				(thermal_gap 0.5)
				(thermal_bridge_width 0.5)
				(island_removal_mode 0)
			)
			(polygon
				(pts
					(xy 452.4248 -5.7658) (xy 452.4248 -5.2578) (xy 452.0438 -5.2578) (xy 452.0438 -5.7658)
				)
			)
		)
	)
	(footprint ""
		(layer "B.Cu")
		(at 282.2448 -77.2414 -90)
		(property "Reference" "R4P4"
			(at 0 0 90)
			(layer "B.SilkS")
			(hide yes)
			(effects
				(font
					(size 1.27 1.27)
				)
				(justify mirror)
			)
		)
		(property "Value" ""
			(at 0 0 90)
			(layer "B.Fab")
			(effects
				(font
					(size 1.27 1.27)
				)
				(justify mirror)
			)
		)
		(duplicate_pad_numbers_are_jumpers no)
		(fp_rect
			(start 0.2794 0.9906)
			(end -0.2794 -0.1016)
			(stroke
				(width 0)
				(type default)
			)
			(fill no)
			(layer "B.CrtYd")
		)
		(fp_line
			(start -0.2794 0.9906)
			(end -0.2794 -0.1016)
			(stroke
				(width 0.1)
				(type default)
			)
			(layer "B.Fab")
		)
		(fp_line
			(start 0.2794 0.9906)
			(end -0.2794 0.9906)
			(stroke
				(width 0.1)
				(type default)
			)
			(layer "B.Fab")
		)
		(fp_line
			(start -0.2794 -0.1016)
			(end 0.2794 -0.1016)
			(stroke
				(width 0.1)
				(type default)
			)
			(layer "B.Fab")
		)
		(fp_line
			(start 0.2794 -0.1016)
			(end 0.2794 0.9906)
			(stroke
				(width 0.1)
				(type default)
			)
			(layer "B.Fab")
		)
		(pad "1" smd rect
			(at 0 0 90)
			(size 0.508 0.508)
			(layers "B.Cu" "B.Mask" "B.Paste")
			(net "A_CPU0_UPI2_RBIAS")
		)
		(pad "2" smd rect
			(at 0 0.889 90)
			(size 0.508 0.508)
			(layers "B.Cu" "B.Mask" "B.Paste")
			(net "GND")
		)
		(zone
			(layer "B.Cu")
			(hatch none 0.5)
			(connect_pads
				(clearance 0)
			)
			(min_thickness 0.25)
			(keepout
				(tracks not_allowed)
				(vias allowed)
				(pads allowed)
				(copperpour not_allowed)
				(footprints allowed)
			)
			(placement
				(enabled no)
				(sheetname "")
			)
			(fill
				(thermal_gap 0.5)
				(thermal_bridge_width 0.5)
				(island_removal_mode 0)
			)
			(polygon
				(pts
					(xy 281.6098 -76.9874) (xy 281.9908 -76.9874) (xy 281.9908 -77.4954) (xy 281.6098 -77.4954)
				)
			)
		)
		(zone
			(layer "B.Cu")
			(hatch none 0.5)
			(connect_pads
				(clearance 0)
			)
			(min_thickness 0.25)
			(keepout
				(tracks allowed)
				(vias not_allowed)
				(pads allowed)
				(copperpour not_allowed)
				(footprints allowed)
			)
			(placement
				(enabled no)
				(sheetname "")
			)
			(fill
				(thermal_gap 0.5)
				(thermal_bridge_width 0.5)
				(island_removal_mode 0)
			)
			(polygon
				(pts
					(xy 281.6098 -76.9874) (xy 281.9908 -76.9874) (xy 281.9908 -77.4954) (xy 281.6098 -77.4954)
				)
			)
		)
	)
)
